# S9S_MB_2U (Grand Teton) — schematic netlist excerpt (pin names and nets, part order shuffled) for the footprints in the layout excerpt that follows; sources: Cadence DE-HDL packaged netlist, KiCad conversion of 03242023_DA0F0TMBIJ0_F0T_Motherboard_J_brd_V01_OCP.brd

R3719  Q_RES  0 5% CHIP  pkg 0402LF  page 233 : A = SMB_LM75_2_3V3AUX_SCL_R ; B = SMB_LM75_2_3V3AUX_SCL
R765  Q_RES  0 5% CHIP  pkg 0402LF  page 131 : A = JTAG_DBP_TCK_PCH ; B = JTAG_DBP_TCK_R_TCK
C928  Q_CAP_DIFFBUS  DIFF BUS_0.22UF 6.3V 20% X6S  pkg C0201  page 173 : \1\ = P5E_CPU0_PE0_TX_C_DN<2> ; \2\ = P5E_CPU0_PE0_TX_DN<2>

(kicad_pcb
	(version 20260206)
	(generator "pcbnew")
	(generator_version "10.0")
	(general
		(thickness 1.6)
		(legacy_teardrops no)
	)
	(paper "A4")
	(title_block
		(title "03242023_DA0F0TMBIJ0_F0T_Motherboard_J_brd_V01_OCP.brd")
		(comment 1 "Grand Teton / footprints 85-87 of 6105")
	)
	(layers
		(0 "F.Cu" signal "TOP")
		(4 "In1.Cu" signal "GND")
		(6 "In2.Cu" signal "IN1")
		(8 "In3.Cu" signal "GND1")
		(10 "In4.Cu" signal "IN2")
		(12 "In5.Cu" signal "GND2")
		(14 "In6.Cu" signal "IN3")
		(16 "In7.Cu" signal "GND3")
		(18 "In8.Cu" signal "VCC")
		(20 "In9.Cu" signal "VCC1")
		(22 "In10.Cu" signal "GND4")
		(24 "In11.Cu" signal "IN4")
		(26 "In12.Cu" signal "GND5")
		(28 "In13.Cu" signal "IN5")
		(30 "In14.Cu" signal "GND6")
		(32 "In15.Cu" signal "IN6")
		(34 "In16.Cu" signal "GND7")
		(2 "B.Cu" signal "BOTTOM")
		(9 "F.Adhes" user "F.Adhesive")
		(11 "B.Adhes" user "B.Adhesive")
		(13 "F.Paste" user "Package Geometry/Pastemask Top")
		(15 "B.Paste" user "Package Geometry/Pastemask Bottom")
		(5 "F.SilkS" user "Ref Des/Silkscreen Top")
		(7 "B.SilkS" user "Ref Des/Silkscreen Bottom")
		(1 "F.Mask" user "Board Geometry/Soldermask Top")
		(3 "B.Mask" user "Board Geometry/Soldermask Bottom")
		(17 "Dwgs.User" user "User.Drawings")
		(19 "Cmts.User" user "User.Comments")
		(21 "Eco1.User" user "User.Eco1")
		(23 "Eco2.User" user "User.Eco2")
		(25 "Edge.Cuts" user "Board Geometry/Outline")
		(27 "Margin" user)
		(31 "F.CrtYd" user "Package Geometry/Place Bound Top")
		(29 "B.CrtYd" user "Package Geometry/Place Bound Bottom")
		(35 "F.Fab" user "Ref Des/Assembly Top")
		(33 "B.Fab" user "Ref Des/Assembly Bottom")
	)
	(footprint ""
		(layer "F.Cu")
		(at 385.384802 -49.488598 90)
		(property "Reference" "R765"
			(at 0 0 90)
			(layer "F.SilkS")
			(hide yes)
			(effects
				(font
					(size 1.27 1.27)
				)
			)
		)
		(property "Value" ""
			(at 0 0 90)
			(layer "F.Fab")
			(effects
				(font
					(size 1.27 1.27)
				)
			)
		)
		(duplicate_pad_numbers_are_jumpers no)
		(fp_line
			(start 0.7874 -0.4064)
			(end 0.7874 0.4064)
			(stroke
				(width 0.1524)
				(type default)
			)
			(layer "F.SilkS")
		)
		(fp_line
			(start -0.7874 -0.4064)
			(end 0.7874 -0.4064)
			(stroke
				(width 0.1524)
				(type default)
			)
			(layer "F.SilkS")
		)
		(fp_line
			(start 0.7874 0.4064)
			(end -0.7874 0.4064)
			(stroke
				(width 0.1524)
				(type default)
			)
			(layer "F.SilkS")
		)
		(fp_line
			(start -0.7874 0.4064)
			(end -0.7874 -0.4064)
			(stroke
				(width 0.1524)
				(type default)
			)
			(layer "F.SilkS")
		)
		(fp_line
			(start -0.12065 -0.305054)
			(end -0.12065 -0.2794)
			(stroke
				(width 0.1)
				(type default)
			)
			(layer "F.Fab")
		)
		(fp_line
			(start -0.67945 -0.305054)
			(end -0.12065 -0.305054)
			(stroke
				(width 0.1)
				(type default)
			)
			(layer "F.Fab")
		)
		(fp_line
			(start 0.67945 -0.3048)
			(end 0.67945 0.3048)
			(stroke
				(width 0.1)
				(type default)
			)
			(layer "F.Fab")
		)
		(fp_line
			(start 0.12065 -0.3048)
			(end 0.67945 -0.3048)
			(stroke
				(width 0.1)
				(type default)
			)
			(layer "F.Fab")
		)
		(fp_line
			(start 0.12065 -0.2794)
			(end 0.12065 -0.3048)
			(stroke
				(width 0.1)
				(type default)
			)
			(layer "F.Fab")
		)
		(fp_line
			(start -0.12065 -0.2794)
			(end 0.12065 -0.2794)
			(stroke
				(width 0.1)
				(type default)
			)
			(layer "F.Fab")
		)
		(fp_line
			(start 0.120396 0.2794)
			(end -0.12065 0.2794)
			(stroke
				(width 0.1)
				(type default)
			)
			(layer "F.Fab")
		)
		(fp_line
			(start -0.12065 0.2794)
			(end -0.12065 0.3048)
			(stroke
				(width 0.1)
				(type default)
			)
			(layer "F.Fab")
		)
		(fp_line
			(start 0.67945 0.3048)
			(end 0.120396 0.3048)
			(stroke
				(width 0.1)
				(type default)
			)
			(layer "F.Fab")
		)
		(fp_line
			(start 0.120396 0.3048)
			(end 0.120396 0.2794)
			(stroke
				(width 0.1)
				(type default)
			)
			(layer "F.Fab")
		)
		(fp_line
			(start -0.12065 0.3048)
			(end -0.67945 0.3048)
			(stroke
				(width 0.1)
				(type default)
			)
			(layer "F.Fab")
		)
		(fp_line
			(start -0.67945 0.3048)
			(end -0.67945 -0.305054)
			(stroke
				(width 0.1)
				(type default)
			)
			(layer "F.Fab")
		)
		(pad "1" smd circle
			(at -0.40005 0 90)
			(size 0 0)
			(layers "F.Cu" "F.Mask" "F.Paste")
			(net "JTAG_DBP_TCK_PCH")
		)
		(pad "2" smd circle
			(at 0.40005 0 90)
			(size 0 0)
			(layers "F.Cu" "F.Mask" "F.Paste")
			(net "JTAG_DBP_TCK_R_TCK")
		)
	)
	(footprint ""
		(layer "F.Cu")
		(at 54.242716 -106.86669 180)
		(property "Reference" "R3719"
			(at 0 0 180)
			(layer "F.SilkS")
			(hide yes)
			(effects
				(font
					(size 1.27 1.27)
				)
			)
		)
		(property "Value" ""
			(at 0 0 180)
			(layer "F.Fab")
			(effects
				(font
					(size 1.27 1.27)
				)
			)
		)
		(duplicate_pad_numbers_are_jumpers no)
		(fp_line
			(start 0.7874 0.4064)
			(end -0.7874 0.4064)
			(stroke
				(width 0.1524)
				(type default)
			)
			(layer "F.SilkS")
		)
		(fp_line
			(start 0.7874 -0.4064)
			(end 0.7874 0.4064)
			(stroke
				(width 0.1524)
				(type default)
			)
			(layer "F.SilkS")
		)
		(fp_line
			(start -0.7874 0.4064)
			(end -0.7874 -0.4064)
			(stroke
				(width 0.1524)
				(type default)
			)
			(layer "F.SilkS")
		)
		(fp_line
			(start -0.7874 -0.4064)
			(end 0.7874 -0.4064)
			(stroke
				(width 0.1524)
				(type default)
			)
			(layer "F.SilkS")
		)
		(fp_line
			(start 0.67945 0.3048)
			(end 0.120396 0.3048)
			(stroke
				(width 0.1)
				(type default)
			)
			(layer "F.Fab")
		)
		(fp_line
			(start 0.67945 -0.3048)
			(end 0.67945 0.3048)
			(stroke
				(width 0.1)
				(type default)
			)
			(layer "F.Fab")
		)
		(fp_line
			(start 0.12065 -0.2794)
			(end 0.12065 -0.3048)
			(stroke
				(width 0.1)
				(type default)
			)
			(layer "F.Fab")
		)
		(fp_line
			(start 0.12065 -0.3048)
			(end 0.67945 -0.3048)
			(stroke
				(width 0.1)
				(type default)
			)
			(layer "F.Fab")
		)
		(fp_line
			(start 0.120396 0.3048)
			(end 0.120396 0.2794)
			(stroke
				(width 0.1)
				(type default)
			)
			(layer "F.Fab")
		)
		(fp_line
			(start 0.120396 0.2794)
			(end -0.12065 0.2794)
			(stroke
				(width 0.1)
				(type default)
			)
			(layer "F.Fab")
		)
		(fp_line
			(start -0.12065 0.3048)
			(end -0.67945 0.3048)
			(stroke
				(width 0.1)
				(type default)
			)
			(layer "F.Fab")
		)
		(fp_line
			(start -0.12065 0.2794)
			(end -0.12065 0.3048)
			(stroke
				(width 0.1)
				(type default)
			)
			(layer "F.Fab")
		)
		(fp_line
			(start -0.12065 -0.2794)
			(end 0.12065 -0.2794)
			(stroke
				(width 0.1)
				(type default)
			)
			(layer "F.Fab")
		)
		(fp_line
			(start -0.12065 -0.305054)
			(end -0.12065 -0.2794)
			(stroke
				(width 0.1)
				(type default)
			)
			(layer "F.Fab")
		)
		(fp_line
			(start -0.67945 0.3048)
			(end -0.67945 -0.305054)
			(stroke
				(width 0.1)
				(type default)
			)
			(layer "F.Fab")
		)
		(fp_line
			(start -0.67945 -0.305054)
			(end -0.12065 -0.305054)
			(stroke
				(width 0.1)
				(type default)
			)
			(layer "F.Fab")
		)
		(pad "1" smd circle
			(at -0.40005 0 180)
			(size 0 0)
			(layers "F.Cu" "F.Mask" "F.Paste")
			(net "SMB_LM75_2_3V3AUX_SCL_R")
		)
		(pad "2" smd circle
			(at 0.40005 0 180)
			(size 0 0)
			(layers "F.Cu" "F.Mask" "F.Paste")
			(net "SMB_LM75_2_3V3AUX_SCL")
		)
	)
	(footprint ""
		(layer "F.Cu")
		(at 345.123008 -408.517344 -90)
		(property "Reference" "C928"
			(at 0 0 270)
			(layer "F.SilkS")
			(hide yes)
			(effects
				(font
					(size 1.27 1.27)
				)
			)
		)
		(property "Value" ""
			(at 0 0 270)
			(layer "F.Fab")
			(effects
				(font
					(size 1.27 1.27)
				)
			)
		)
		(duplicate_pad_numbers_are_jumpers no)
		(fp_line
			(start -0.299974 0.150114)
			(end -0.299974 -0.150114)
			(stroke
				(width 0.1)
				(type default)
			)
			(layer "F.Fab")
		)
		(fp_line
			(start 0.299974 0.150114)
			(end -0.299974 0.150114)
			(stroke
				(width 0.1)
				(type default)
			)
			(layer "F.Fab")
		)
		(fp_line
			(start -0.299974 -0.150114)
			(end 0.299974 -0.150114)
			(stroke
				(width 0.1)
				(type default)
			)
			(layer "F.Fab")
		)
		(fp_line
			(start 0.299974 -0.150114)
			(end 0.299974 0.150114)
			(stroke
				(width 0.1)
				(type default)
			)
			(layer "F.Fab")
		)
		(pad "1" smd rect
			(at -0.2667 0 270)
			(size 0.3048 0.381)
			(layers "F.Cu" "F.Mask" "F.Paste")
			(net "P5E_CPU0_PE0_TX_C_DN<2>")
		)
		(pad "2" smd rect
			(at 0.2667 0 270)
			(size 0.3048 0.381)
			(layers "F.Cu" "F.Mask" "F.Paste")
			(net "P5E_CPU0_PE0_TX_DN<2>")
		)
	)
)
